(kicad_pcb
	(version 20260206)
	(generator "pcbnew")
	(generator_version "10.0")
	(general
		(thickness 1.6)
		(legacy_teardrops no)
	)
	(paper "A4")
	(title_block
		(title "01162023_DA0F0TEBIF0_F0T_Expander_BD_F_brd_V02_OCP.brd")
		(comment 1 "Grand Teton / footprints 3960-3966 of 9728")
	)
	(layers
		(0 "F.Cu" signal "TOP")
		(4 "In1.Cu" signal "GND")
		(6 "In2.Cu" signal "VCC")
		(8 "In3.Cu" signal "VCC1")
		(10 "In4.Cu" signal "GND1")
		(12 "In5.Cu" signal "IN1")
		(14 "In6.Cu" signal "GND2")
		(16 "In7.Cu" signal "IN2")
		(18 "In8.Cu" signal "GND3")
		(20 "In9.Cu" signal "IN3")
		(22 "In10.Cu" signal "GND4")
		(24 "In11.Cu" signal "IN4")
		(26 "In12.Cu" signal "GND5")
		(28 "In13.Cu" signal "IN5")
		(30 "In14.Cu" signal "GND6")
		(32 "In15.Cu" signal "IN6")
		(34 "In16.Cu" signal "GND7")
		(2 "B.Cu" signal "BOTTOM")
		(9 "F.Adhes" user "F.Adhesive")
		(11 "B.Adhes" user "B.Adhesive")
		(13 "F.Paste" user "Package Geometry/Pastemask Top")
		(15 "B.Paste" user "Package Geometry/Pastemask Bottom")
		(5 "F.SilkS" user "Ref Des/Silkscreen Top")
		(7 "B.SilkS" user "Ref Des/Silkscreen Bottom")
		(1 "F.Mask" user "Board Geometry/Soldermask Top")
		(3 "B.Mask" user "Board Geometry/Soldermask Bottom")
		(17 "Dwgs.User" user "User.Drawings")
		(19 "Cmts.User" user "User.Comments")
		(21 "Eco1.User" user "User.Eco1")
		(23 "Eco2.User" user "User.Eco2")
		(25 "Edge.Cuts" user "Board Geometry/Outline")
		(27 "Margin" user)
		(31 "F.CrtYd" user "Package Geometry/Place Bound Top")
		(29 "B.CrtYd" user "Package Geometry/Place Bound Bottom")
		(35 "F.Fab" user "Ref Des/Assembly Top")
		(33 "B.Fab" user "Ref Des/Assembly Bottom")
	)
	(footprint ""
		(layer "F.Cu")
		(at 291.194998 -98.734372)
		(property "Reference" "R256"
			(at 0 0 0)
			(layer "F.SilkS")
			(hide yes)
			(effects
				(font
					(size 1.27 1.27)
				)
			)
		)
		(property "Value" ""
			(at 0 0 0)
			(layer "F.Fab")
			(effects
				(font
					(size 1.27 1.27)
				)
			)
		)
		(duplicate_pad_numbers_are_jumpers no)
		(fp_line
			(start -0.7874 -0.4064)
			(end 0.7874 -0.4064)
			(stroke
				(width 0.1524)
				(type default)
			)
			(layer "F.SilkS")
		)
		(fp_line
			(start -0.7874 0.4064)
			(end -0.7874 -0.4064)
			(stroke
				(width 0.1524)
				(type default)
			)
			(layer "F.SilkS")
		)
		(fp_line
			(start 0.7874 -0.4064)
			(end 0.7874 0.4064)
			(stroke
				(width 0.1524)
				(type default)
			)
			(layer "F.SilkS")
		)
		(fp_line
			(start 0.7874 0.4064)
			(end -0.7874 0.4064)
			(stroke
				(width 0.1524)
				(type default)
			)
			(layer "F.SilkS")
		)
		(fp_line
			(start -0.67945 -0.305054)
			(end -0.12065 -0.305054)
			(stroke
				(width 0.1)
				(type default)
			)
			(layer "F.Fab")
		)
		(fp_line
			(start -0.67945 0.3048)
			(end -0.67945 -0.305054)
			(stroke
				(width 0.1)
				(type default)
			)
			(layer "F.Fab")
		)
		(fp_line
			(start -0.12065 -0.305054)
			(end -0.12065 -0.2794)
			(stroke
				(width 0.1)
				(type default)
			)
			(layer "F.Fab")
		)
		(fp_line
			(start -0.12065 -0.2794)
			(end 0.12065 -0.2794)
			(stroke
				(width 0.1)
				(type default)
			)
			(layer "F.Fab")
		)
		(fp_line
			(start -0.12065 0.2794)
			(end -0.12065 0.3048)
			(stroke
				(width 0.1)
				(type default)
			)
			(layer "F.Fab")
		)
		(fp_line
			(start -0.12065 0.3048)
			(end -0.67945 0.3048)
			(stroke
				(width 0.1)
				(type default)
			)
			(layer "F.Fab")
		)
		(fp_line
			(start 0.120396 0.2794)
			(end -0.12065 0.2794)
			(stroke
				(width 0.1)
				(type default)
			)
			(layer "F.Fab")
		)
		(fp_line
			(start 0.120396 0.3048)
			(end 0.120396 0.2794)
			(stroke
				(width 0.1)
				(type default)
			)
			(layer "F.Fab")
		)
		(fp_line
			(start 0.12065 -0.3048)
			(end 0.67945 -0.3048)
			(stroke
				(width 0.1)
				(type default)
			)
			(layer "F.Fab")
		)
		(fp_line
			(start 0.12065 -0.2794)
			(end 0.12065 -0.3048)
			(stroke
				(width 0.1)
				(type default)
			)
			(layer "F.Fab")
		)
		(fp_line
			(start 0.67945 -0.3048)
			(end 0.67945 0.3048)
			(stroke
				(width 0.1)
				(type default)
			)
			(layer "F.Fab")
		)
		(fp_line
			(start 0.67945 0.3048)
			(end 0.120396 0.3048)
			(stroke
				(width 0.1)
				(type default)
			)
			(layer "F.Fab")
		)
		(pad "1" smd circle
			(at -0.40005 0)
			(size 0 0)
			(layers "F.Cu" "F.Mask" "F.Paste")
			(net "NIC5_RBT_ARB_OUT")
		)
		(pad "2" smd circle
			(at 0.40005 0)
			(size 0 0)
			(layers "F.Cu" "F.Mask" "F.Paste")
			(net "NIC5_RBT_ARB_IN")
		)
	)
	(footprint ""
		(layer "F.Cu")
		(at 58.176922 -376.540268)
		(property "Reference" "R1870"
			(at 0 0 0)
			(layer "F.SilkS")
			(hide yes)
			(effects
				(font
					(size 1.27 1.27)
				)
			)
		)
		(property "Value" ""
			(at 0 0 0)
			(layer "F.Fab")
			(effects
				(font
					(size 1.27 1.27)
				)
			)
		)
		(duplicate_pad_numbers_are_jumpers no)
		(fp_line
			(start -0.7874 -0.4064)
			(end 0.7874 -0.4064)
			(stroke
				(width 0.1524)
				(type default)
			)
			(layer "F.SilkS")
		)
		(fp_line
			(start -0.7874 0.4064)
			(end -0.7874 -0.4064)
			(stroke
				(width 0.1524)
				(type default)
			)
			(layer "F.SilkS")
		)
		(fp_line
			(start 0.7874 -0.4064)
			(end 0.7874 0.4064)
			(stroke
				(width 0.1524)
				(type default)
			)
			(layer "F.SilkS")
		)
		(fp_line
			(start 0.7874 0.4064)
			(end -0.7874 0.4064)
			(stroke
				(width 0.1524)
				(type default)
			)
			(layer "F.SilkS")
		)
		(fp_line
			(start -0.67945 -0.305054)
			(end -0.12065 -0.305054)
			(stroke
				(width 0.1)
				(type default)
			)
			(layer "F.Fab")
		)
		(fp_line
			(start -0.67945 0.3048)
			(end -0.67945 -0.305054)
			(stroke
				(width 0.1)
				(type default)
			)
			(layer "F.Fab")
		)
		(fp_line
			(start -0.12065 -0.305054)
			(end -0.12065 -0.2794)
			(stroke
				(width 0.1)
				(type default)
			)
			(layer "F.Fab")
		)
		(fp_line
			(start -0.12065 -0.2794)
			(end 0.12065 -0.2794)
			(stroke
				(width 0.1)
				(type default)
			)
			(layer "F.Fab")
		)
		(fp_line
			(start -0.12065 0.2794)
			(end -0.12065 0.3048)
			(stroke
				(width 0.1)
				(type default)
			)
			(layer "F.Fab")
		)
		(fp_line
			(start -0.12065 0.3048)
			(end -0.67945 0.3048)
			(stroke
				(width 0.1)
				(type default)
			)
			(layer "F.Fab")
		)
		(fp_line
			(start 0.120396 0.2794)
			(end -0.12065 0.2794)
			(stroke
				(width 0.1)
				(type default)
			)
			(layer "F.Fab")
		)
		(fp_line
			(start 0.120396 0.3048)
			(end 0.120396 0.2794)
			(stroke
				(width 0.1)
				(type default)
			)
			(layer "F.Fab")
		)
		(fp_line
			(start 0.12065 -0.3048)
			(end 0.67945 -0.3048)
			(stroke
				(width 0.1)
				(type default)
			)
			(layer "F.Fab")
		)
		(fp_line
			(start 0.12065 -0.2794)
			(end 0.12065 -0.3048)
			(stroke
				(width 0.1)
				(type default)
			)
			(layer "F.Fab")
		)
		(fp_line
			(start 0.67945 -0.3048)
			(end 0.67945 0.3048)
			(stroke
				(width 0.1)
				(type default)
			)
			(layer "F.Fab")
		)
		(fp_line
			(start 0.67945 0.3048)
			(end 0.120396 0.3048)
			(stroke
				(width 0.1)
				(type default)
			)
			(layer "F.Fab")
		)
		(pad "1" smd circle
			(at -0.40005 0)
			(size 0 0)
			(layers "F.Cu" "F.Mask" "F.Paste")
			(net "GPU_BASE_PWR_EN_R")
		)
		(pad "2" smd circle
			(at 0.40005 0)
			(size 0 0)
			(layers "F.Cu" "F.Mask" "F.Paste")
			(net "GPU_BASE_PWR_EN")
		)
	)
	(footprint ""
		(layer "F.Cu")
		(at 386.899912 -154.327352 180)
		(property "Reference" "R332"
			(at 0 0 180)
			(layer "F.SilkS")
			(hide yes)
			(effects
				(font
					(size 1.27 1.27)
				)
			)
		)
		(property "Value" ""
			(at 0 0 180)
			(layer "F.Fab")
			(effects
				(font
					(size 1.27 1.27)
				)
			)
		)
		(duplicate_pad_numbers_are_jumpers no)
		(fp_line
			(start 0.7874 0.4064)
			(end -0.7874 0.4064)
			(stroke
				(width 0.1524)
				(type default)
			)
			(layer "F.SilkS")
		)
		(fp_line
			(start 0.7874 -0.4064)
			(end 0.7874 0.4064)
			(stroke
				(width 0.1524)
				(type default)
			)
			(layer "F.SilkS")
		)
		(fp_line
			(start -0.7874 0.4064)
			(end -0.7874 -0.4064)
			(stroke
				(width 0.1524)
				(type default)
			)
			(layer "F.SilkS")
		)
		(fp_line
			(start -0.7874 -0.4064)
			(end 0.7874 -0.4064)
			(stroke
				(width 0.1524)
				(type default)
			)
			(layer "F.SilkS")
		)
		(fp_line
			(start 0.67945 0.3048)
			(end 0.120396 0.3048)
			(stroke
				(width 0.1)
				(type default)
			)
			(layer "F.Fab")
		)
		(fp_line
			(start 0.67945 -0.3048)
			(end 0.67945 0.3048)
			(stroke
				(width 0.1)
				(type default)
			)
			(layer "F.Fab")
		)
		(fp_line
			(start 0.12065 -0.2794)
			(end 0.12065 -0.3048)
			(stroke
				(width 0.1)
				(type default)
			)
			(layer "F.Fab")
		)
		(fp_line
			(start 0.12065 -0.3048)
			(end 0.67945 -0.3048)
			(stroke
				(width 0.1)
				(type default)
			)
			(layer "F.Fab")
		)
		(fp_line
			(start 0.120396 0.3048)
			(end 0.120396 0.2794)
			(stroke
				(width 0.1)
				(type default)
			)
			(layer "F.Fab")
		)
		(fp_line
			(start 0.120396 0.2794)
			(end -0.12065 0.2794)
			(stroke
				(width 0.1)
				(type default)
			)
			(layer "F.Fab")
		)
		(fp_line
			(start -0.12065 0.3048)
			(end -0.67945 0.3048)
			(stroke
				(width 0.1)
				(type default)
			)
			(layer "F.Fab")
		)
		(fp_line
			(start -0.12065 0.2794)
			(end -0.12065 0.3048)
			(stroke
				(width 0.1)
				(type default)
			)
			(layer "F.Fab")
		)
		(fp_line
			(start -0.12065 -0.2794)
			(end 0.12065 -0.2794)
			(stroke
				(width 0.1)
				(type default)
			)
			(layer "F.Fab")
		)
		(fp_line
			(start -0.12065 -0.305054)
			(end -0.12065 -0.2794)
			(stroke
				(width 0.1)
				(type default)
			)
			(layer "F.Fab")
		)
		(fp_line
			(start -0.67945 0.3048)
			(end -0.67945 -0.305054)
			(stroke
				(width 0.1)
				(type default)
			)
			(layer "F.Fab")
		)
		(fp_line
			(start -0.67945 -0.305054)
			(end -0.12065 -0.305054)
			(stroke
				(width 0.1)
				(type default)
			)
			(layer "F.Fab")
		)
		(pad "1" smd circle
			(at -0.40005 0 180)
			(size 0 0)
			(layers "F.Cu" "F.Mask" "F.Paste")
			(net "NIC6_SLOT_ID0")
		)
		(pad "2" smd circle
			(at 0.40005 0 180)
			(size 0 0)
			(layers "F.Cu" "F.Mask" "F.Paste")
			(net "GND")
		)
	)
	(footprint ""
		(layer "F.Cu")
		(at 126.210314 -123.947428 180)
		(property "Reference" "PR249"
			(at 0 0 180)
			(layer "F.SilkS")
			(hide yes)
			(effects
				(font
					(size 1.27 1.27)
				)
			)
		)
		(property "Value" ""
			(at 0 0 180)
			(layer "F.Fab")
			(effects
				(font
					(size 1.27 1.27)
				)
			)
		)
		(duplicate_pad_numbers_are_jumpers no)
		(fp_line
			(start 0.7874 0.4064)
			(end -0.7874 0.4064)
			(stroke
				(width 0.1524)
				(type default)
			)
			(layer "F.SilkS")
		)
		(fp_line
			(start 0.7874 -0.4064)
			(end 0.7874 0.4064)
			(stroke
				(width 0.1524)
				(type default)
			)
			(layer "F.SilkS")
		)
		(fp_line
			(start -0.7874 0.4064)
			(end -0.7874 -0.4064)
			(stroke
				(width 0.1524)
				(type default)
			)
			(layer "F.SilkS")
		)
		(fp_line
			(start -0.7874 -0.4064)
			(end 0.7874 -0.4064)
			(stroke
				(width 0.1524)
				(type default)
			)
			(layer "F.SilkS")
		)
		(fp_line
			(start 0.67945 0.3048)
			(end 0.120396 0.3048)
			(stroke
				(width 0.1)
				(type default)
			)
			(layer "F.Fab")
		)
		(fp_line
			(start 0.67945 -0.3048)
			(end 0.67945 0.3048)
			(stroke
				(width 0.1)
				(type default)
			)
			(layer "F.Fab")
		)
		(fp_line
			(start 0.12065 -0.2794)
			(end 0.12065 -0.3048)
			(stroke
				(width 0.1)
				(type default)
			)
			(layer "F.Fab")
		)
		(fp_line
			(start 0.12065 -0.3048)
			(end 0.67945 -0.3048)
			(stroke
				(width 0.1)
				(type default)
			)
			(layer "F.Fab")
		)
		(fp_line
			(start 0.120396 0.3048)
			(end 0.120396 0.2794)
			(stroke
				(width 0.1)
				(type default)
			)
			(layer "F.Fab")
		)
		(fp_line
			(start 0.120396 0.2794)
			(end -0.12065 0.2794)
			(stroke
				(width 0.1)
				(type default)
			)
			(layer "F.Fab")
		)
		(fp_line
			(start -0.12065 0.3048)
			(end -0.67945 0.3048)
			(stroke
				(width 0.1)
				(type default)
			)
			(layer "F.Fab")
		)
		(fp_line
			(start -0.12065 0.2794)
			(end -0.12065 0.3048)
			(stroke
				(width 0.1)
				(type default)
			)
			(layer "F.Fab")
		)
		(fp_line
			(start -0.12065 -0.2794)
			(end 0.12065 -0.2794)
			(stroke
				(width 0.1)
				(type default)
			)
			(layer "F.Fab")
		)
		(fp_line
			(start -0.12065 -0.305054)
			(end -0.12065 -0.2794)
			(stroke
				(width 0.1)
				(type default)
			)
			(layer "F.Fab")
		)
		(fp_line
			(start -0.67945 0.3048)
			(end -0.67945 -0.305054)
			(stroke
				(width 0.1)
				(type default)
			)
			(layer "F.Fab")
		)
		(fp_line
			(start -0.67945 -0.305054)
			(end -0.12065 -0.305054)
			(stroke
				(width 0.1)
				(type default)
			)
			(layer "F.Fab")
		)
		(pad "1" smd circle
			(at -0.40005 0 180)
			(size 0 0)
			(layers "F.Cu" "F.Mask" "F.Paste")
			(net "P3V3_NIC2_OCP")
		)
		(pad "2" smd circle
			(at 0.40005 0 180)
			(size 0 0)
			(layers "F.Cu" "F.Mask" "F.Paste")
			(net "GND")
		)
	)
	(footprint ""
		(layer "F.Cu")
		(at 132.29463 -111.377476 -90)
		(property "Reference" "PC794"
			(at 0 0 270)
			(layer "F.SilkS")
			(hide yes)
			(effects
				(font
					(size 1.27 1.27)
				)
			)
		)
		(property "Value" ""
			(at 0 0 270)
			(layer "F.Fab")
			(effects
				(font
					(size 1.27 1.27)
				)
			)
		)
		(duplicate_pad_numbers_are_jumpers no)
		(fp_line
			(start -0.7874 0.4064)
			(end -0.7874 -0.4064)
			(stroke
				(width 0.1524)
				(type default)
			)
			(layer "F.SilkS")
		)
		(fp_line
			(start 0.7874 0.4064)
			(end -0.7874 0.4064)
			(stroke
				(width 0.1524)
				(type default)
			)
			(layer "F.SilkS")
		)
		(fp_line
			(start -0.7874 -0.4064)
			(end 0.7874 -0.4064)
			(stroke
				(width 0.1524)
				(type default)
			)
			(layer "F.SilkS")
		)
		(fp_line
			(start 0.7874 -0.4064)
			(end 0.7874 0.4064)
			(stroke
				(width 0.1524)
				(type default)
			)
			(layer "F.SilkS")
		)
		(fp_line
			(start -0.67945 0.3048)
			(end -0.67945 -0.305054)
			(stroke
				(width 0.1)
				(type default)
			)
			(layer "F.Fab")
		)
		(fp_line
			(start -0.12065 0.3048)
			(end -0.67945 0.3048)
			(stroke
				(width 0.1)
				(type default)
			)
			(layer "F.Fab")
		)
		(fp_line
			(start 0.120396 0.3048)
			(end 0.120396 0.2794)
			(stroke
				(width 0.1)
				(type default)
			)
			(layer "F.Fab")
		)
		(fp_line
			(start 0.67945 0.3048)
			(end 0.120396 0.3048)
			(stroke
				(width 0.1)
				(type default)
			)
			(layer "F.Fab")
		)
		(fp_line
			(start -0.12065 0.2794)
			(end -0.12065 0.3048)
			(stroke
				(width 0.1)
				(type default)
			)
			(layer "F.Fab")
		)
		(fp_line
			(start 0.120396 0.2794)
			(end -0.12065 0.2794)
			(stroke
				(width 0.1)
				(type default)
			)
			(layer "F.Fab")
		)
		(fp_line
			(start -0.12065 -0.2794)
			(end 0.12065 -0.2794)
			(stroke
				(width 0.1)
				(type default)
			)
			(layer "F.Fab")
		)
		(fp_line
			(start 0.12065 -0.2794)
			(end 0.12065 -0.3048)
			(stroke
				(width 0.1)
				(type default)
			)
			(layer "F.Fab")
		)
		(fp_line
			(start 0.12065 -0.3048)
			(end 0.67945 -0.3048)
			(stroke
				(width 0.1)
				(type default)
			)
			(layer "F.Fab")
		)
		(fp_line
			(start 0.67945 -0.3048)
			(end 0.67945 0.3048)
			(stroke
				(width 0.1)
				(type default)
			)
			(layer "F.Fab")
		)
		(fp_line
			(start -0.67945 -0.305054)
			(end -0.12065 -0.305054)
			(stroke
				(width 0.1)
				(type default)
			)
			(layer "F.Fab")
		)
		(fp_line
			(start -0.12065 -0.305054)
			(end -0.12065 -0.2794)
			(stroke
				(width 0.1)
				(type default)
			)
			(layer "F.Fab")
		)
		(pad "1" smd circle
			(at -0.40005 0 270)
			(size 0 0)
			(layers "F.Cu" "F.Mask" "F.Paste")
			(net "P3V3_NIC2_CO_MODE")
		)
		(pad "2" smd circle
			(at 0.40005 0 270)
			(size 0 0)
			(layers "F.Cu" "F.Mask" "F.Paste")
			(net "GND")
		)
	)
	(footprint ""
		(layer "F.Cu")
		(at 72.43445 -34.546286 180)
		(property "Reference" "C81"
			(at 0 0 180)
			(layer "F.SilkS")
			(hide yes)
			(effects
				(font
					(size 1.27 1.27)
				)
			)
		)
		(property "Value" ""
			(at 0 0 180)
			(layer "F.Fab")
			(effects
				(font
					(size 1.27 1.27)
				)
			)
		)
		(duplicate_pad_numbers_are_jumpers no)
		(fp_line
			(start 0.299974 0.150114)
			(end -0.299974 0.150114)
			(stroke
				(width 0.1)
				(type default)
			)
			(layer "F.Fab")
		)
		(fp_line
			(start 0.299974 -0.150114)
			(end 0.299974 0.150114)
			(stroke
				(width 0.1)
				(type default)
			)
			(layer "F.Fab")
		)
		(fp_line
			(start -0.299974 0.150114)
			(end -0.299974 -0.150114)
			(stroke
				(width 0.1)
				(type default)
			)
			(layer "F.Fab")
		)
		(fp_line
			(start -0.299974 -0.150114)
			(end 0.299974 -0.150114)
			(stroke
				(width 0.1)
				(type default)
			)
			(layer "F.Fab")
		)
		(pad "1" smd rect
			(at -0.2667 0 180)
			(size 0.3048 0.381)
			(layers "F.Cu" "F.Mask" "F.Paste")
			(net "P5E_PEX0_STN2_TX_DP<39>")
		)
		(pad "2" smd rect
			(at 0.2667 0 180)
			(size 0.3048 0.381)
			(layers "F.Cu" "F.Mask" "F.Paste")
			(net "P5E_PEX0_STN2_TX_C_DP<39>")
		)
	)
	(footprint ""
		(layer "F.Cu")
		(at 247.673114 -210.288378)
		(property "Reference" "R6714"
			(at 0 0 0)
			(layer "F.SilkS")
			(hide yes)
			(effects
				(font
					(size 1.27 1.27)
				)
			)
		)
		(property "Value" ""
			(at 0 0 0)
			(layer "F.Fab")
			(effects
				(font
					(size 1.27 1.27)
				)
			)
		)
		(duplicate_pad_numbers_are_jumpers no)
		(fp_line
			(start -0.7874 -0.4064)
			(end 0.7874 -0.4064)
			(stroke
				(width 0.1524)
				(type default)
			)
			(layer "F.SilkS")
		)
		(fp_line
			(start -0.7874 0.4064)
			(end -0.7874 -0.4064)
			(stroke
				(width 0.1524)
				(type default)
			)
			(layer "F.SilkS")
		)
		(fp_line
			(start 0.7874 -0.4064)
			(end 0.7874 0.4064)
			(stroke
				(width 0.1524)
				(type default)
			)
			(layer "F.SilkS")
		)
		(fp_line
			(start 0.7874 0.4064)
			(end -0.7874 0.4064)
			(stroke
				(width 0.1524)
				(type default)
			)
			(layer "F.SilkS")
		)
		(fp_line
			(start -0.67945 -0.305054)
			(end -0.12065 -0.305054)
			(stroke
				(width 0.1)
				(type default)
			)
			(layer "F.Fab")
		)
		(fp_line
			(start -0.67945 0.3048)
			(end -0.67945 -0.305054)
			(stroke
				(width 0.1)
				(type default)
			)
			(layer "F.Fab")
		)
		(fp_line
			(start -0.12065 -0.305054)
			(end -0.12065 -0.2794)
			(stroke
				(width 0.1)
				(type default)
			)
			(layer "F.Fab")
		)
		(fp_line
			(start -0.12065 -0.2794)
			(end 0.12065 -0.2794)
			(stroke
				(width 0.1)
				(type default)
			)
			(layer "F.Fab")
		)
		(fp_line
			(start -0.12065 0.2794)
			(end -0.12065 0.3048)
			(stroke
				(width 0.1)
				(type default)
			)
			(layer "F.Fab")
		)
		(fp_line
			(start -0.12065 0.3048)
			(end -0.67945 0.3048)
			(stroke
				(width 0.1)
				(type default)
			)
			(layer "F.Fab")
		)
		(fp_line
			(start 0.120396 0.2794)
			(end -0.12065 0.2794)
			(stroke
				(width 0.1)
				(type default)
			)
			(layer "F.Fab")
		)
		(fp_line
			(start 0.120396 0.3048)
			(end 0.120396 0.2794)
			(stroke
				(width 0.1)
				(type default)
			)
			(layer "F.Fab")
		)
		(fp_line
			(start 0.12065 -0.3048)
			(end 0.67945 -0.3048)
			(stroke
				(width 0.1)
				(type default)
			)
			(layer "F.Fab")
		)
		(fp_line
			(start 0.12065 -0.2794)
			(end 0.12065 -0.3048)
			(stroke
				(width 0.1)
				(type default)
			)
			(layer "F.Fab")
		)
		(fp_line
			(start 0.67945 -0.3048)
			(end 0.67945 0.3048)
			(stroke
				(width 0.1)
				(type default)
			)
			(layer "F.Fab")
		)
		(fp_line
			(start 0.67945 0.3048)
			(end 0.120396 0.3048)
			(stroke
				(width 0.1)
				(type default)
			)
			(layer "F.Fab")
		)
		(pad "1" smd circle
			(at -0.40005 0)
			(size 0 0)
			(layers "F.Cu" "F.Mask" "F.Paste")
			(net "HSC_TYPE_ADC_R")
		)
		(pad "2" smd circle
			(at 0.40005 0)
			(size 0 0)
			(layers "F.Cu" "F.Mask" "F.Paste")
			(net "GND")
		)
	)
)
